(kicad_pcb
	(version 20241229)
	(generator "pcbnew")
	(generator_version "9.0")
	(general
		(thickness 1.258)
		(legacy_teardrops no)
	)
	(paper "A4")
	(title_block
		(date "2024-05-27")
		(rev "1.1.2")
		(comment 9 "footprints 15-18 of 64")
	)
	(layers
		(0 "F.Cu" signal)
		(4 "In1.Cu" power)
		(6 "In2.Cu" power)
		(8 "In3.Cu" signal)
		(10 "In4.Cu" signal)
		(2 "B.Cu" signal)
		(9 "F.Adhes" user "F.Adhesive")
		(11 "B.Adhes" user "B.Adhesive")
		(13 "F.Paste" user)
		(15 "B.Paste" user)
		(5 "F.SilkS" user "F.Silkscreen")
		(7 "B.SilkS" user "B.Silkscreen")
		(1 "F.Mask" user)
		(3 "B.Mask" user)
		(17 "Dwgs.User" user "User.Drawings")
		(19 "Cmts.User" user "User.Comments")
		(21 "Eco1.User" user "User.Eco1")
		(23 "Eco2.User" user "User.Eco2")
		(25 "Edge.Cuts" user)
		(27 "Margin" user)
		(31 "F.CrtYd" user "F.Courtyard")
		(29 "B.CrtYd" user "B.Courtyard")
		(35 "F.Fab" user)
		(33 "B.Fab" user)
	)
	(footprint "antmicro-footprints:SOT-23-5"
		(layer "F.Cu")
		(at 131.525 83.55 180)
		(property "Reference" "U2"
			(at -2.485 1.54 0)
			(layer "F.SilkS")
			(effects
				(font
					(size 0.7 0.7)
					(thickness 0.15)
				)
				(justify right bottom)
			)
		)
		(property "Value" "TPS613221A_SOT-23-5"
			(at 0.002 2.799 0)
			(layer "F.Fab")
			(hide yes)
			(effects
				(font
					(size 0.7 0.7)
					(thickness 0.15)
				)
				(justify right bottom)
			)
		)
		(property "Description" "1.8-A switch current boost converter 6.5-μA Quiescent current"
			(at 0 0 180)
			(layer "F.Fab")
			(hide yes)
			(effects
				(font
					(size 1.27 1.27)
					(thickness 0.15)
				)
			)
		)
		(property "Author" "Antmicro"
			(at 263.05 167.1 0)
			(layer "F.Fab")
			(hide yes)
			(effects
				(font
					(size 1 1)
					(thickness 0.15)
				)
			)
		)
		(property "License" "Apache-2.0"
			(at 263.05 167.1 0)
			(layer "F.Fab")
			(hide yes)
			(effects
				(font
					(size 1 1)
					(thickness 0.15)
				)
			)
		)
		(property "MPN" "TPS613221ADBVT"
			(at 263.05 167.1 0)
			(layer "F.Fab")
			(hide yes)
			(effects
				(font
					(size 1 1)
					(thickness 0.15)
				)
			)
		)
		(property "Manufacturer" "Texas Instruments"
			(at 263.05 167.1 0)
			(layer "F.Fab")
			(hide yes)
			(effects
				(font
					(size 1 1)
					(thickness 0.15)
				)
			)
		)
		(sheetname "EEPROM")
		(sheetfile "EEPROM.kicad_sch")
		(attr smd)
		(fp_line
			(start 0.8 1.599)
			(end 0.549 1.599)
			(stroke
				(width 0.15)
				(type solid)
			)
			(layer "F.SilkS")
		)
		(fp_line
			(start 0.8 1.3)
			(end 0.8 1.599)
			(stroke
				(width 0.15)
				(type solid)
			)
			(layer "F.SilkS")
		)
		(fp_line
			(start 0.8 0.55)
			(end 0.8 -0.55)
			(stroke
				(width 0.15)
				(type solid)
			)
			(layer "F.SilkS")
		)
		(fp_line
			(start 0.8 -1.3)
			(end 0.8 -1.6)
			(stroke
				(width 0.15)
				(type solid)
			)
			(layer "F.SilkS")
		)
		(fp_line
			(start 0.8 -1.6)
			(end 0.5 -1.6)
			(stroke
				(width 0.15)
				(type solid)
			)
			(layer "F.SilkS")
		)
		(fp_line
			(start -0.55 1.6)
			(end -0.85 1.6)
			(stroke
				(width 0.15)
				(type solid)
			)
			(layer "F.SilkS")
		)
		(fp_line
			(start -0.8 -1.6)
			(end -0.5 -1.6)
			(stroke
				(width 0.15)
				(type solid)
			)
			(layer "F.SilkS")
		)
		(fp_line
			(start -0.8 -1.6)
			(end -0.8 -1.3)
			(stroke
				(width 0.15)
				(type solid)
			)
			(layer "F.SilkS")
		)
		(fp_line
			(start -0.85 1.6)
			(end -0.85 1.301)
			(stroke
				(width 0.15)
				(type solid)
			)
			(layer "F.SilkS")
		)
		(fp_circle
			(center -1.25 -1.5)
			(end -1.2 -1.5)
			(stroke
				(width 0.15)
				(type solid)
			)
			(fill yes)
			(layer "F.SilkS")
		)
		(fp_rect
			(start 1.9 -1.76)
			(end -1.9 1.75)
			(stroke
				(width 0.05)
				(type solid)
			)
			(fill no)
			(layer "F.CrtYd")
		)
		(fp_line
			(start -0.398 -1.526)
			(end -0.874 -1.05)
			(stroke
				(width 0.15)
				(type solid)
			)
			(layer "F.Fab")
		)
		(fp_rect
			(start 0.874 1.523)
			(end -0.873 -1.525)
			(stroke
				(width 0.15)
				(type solid)
			)
			(fill no)
			(layer "F.Fab")
		)
		(pad "1" smd rect
			(at -1.351 -0.951 90)
			(size 0.55 1)
			(layers "F.Cu" "F.Mask" "F.Paste")
			(net 69 "Net-(U2-SW)")
			(pinfunction "SW")
			(pintype "power_in")
		)
		(pad "2" smd rect
			(at -1.351 0 90)
			(size 0.55 1)
			(layers "F.Cu" "F.Mask" "F.Paste")
			(net 1 "GND")
			(pinfunction "GND")
			(pintype "power_in")
		)
		(pad "3" smd rect
			(at -1.351 0.949 90)
			(size 0.55 1)
			(layers "F.Cu" "F.Mask" "F.Paste")
			(net 223 "unconnected-(U2-NC-Pad3)")
			(pinfunction "NC")
			(pintype "no_connect")
		)
		(pad "4" smd rect
			(at 1.35 0.949 90)
			(size 0.55 1)
			(layers "F.Cu" "F.Mask" "F.Paste")
			(net 52 "/EEPROM/VDD_LED")
			(pinfunction "VOUT")
			(pintype "power_in")
		)
		(pad "5" smd rect
			(at 1.35 -0.951 90)
			(size 0.55 1)
			(layers "F.Cu" "F.Mask" "F.Paste")
			(net 224 "unconnected-(U2-NC-Pad5)")
			(pinfunction "NC")
			(pintype "no_connect")
		)
	)
	(footprint "antmicro-footprints:TSSOP-16_4.4x5mm_P0.65mm"
		(layer "F.Cu")
		(at 125.125 84.9)
		(property "Reference" "IC1"
			(at -2.655 3.76 0)
			(layer "F.SilkS")
			(effects
				(font
					(size 0.7 0.7)
					(thickness 0.15)
				)
				(justify left bottom)
			)
		)
		(property "Value" "PCA6408A_TSSOP"
			(at 0 3.749 0)
			(layer "F.Fab")
			(hide yes)
			(effects
				(font
					(size 0.7 0.7)
					(thickness 0.15)
				)
				(justify left bottom)
			)
		)
		(property "Description" "Low-voltage, 8-bit I2C-bus and SMBus I/O expander"
			(at 0 0 0)
			(layer "F.Fab")
			(hide yes)
			(effects
				(font
					(size 1.27 1.27)
					(thickness 0.15)
				)
			)
		)
		(property "Author" "Antmicro"
			(at 0 0 0)
			(layer "F.Fab")
			(hide yes)
			(effects
				(font
					(size 1 1)
					(thickness 0.15)
				)
			)
		)
		(property "License" "Apache-2.0"
			(at 0 0 0)
			(layer "F.Fab")
			(hide yes)
			(effects
				(font
					(size 1 1)
					(thickness 0.15)
				)
			)
		)
		(property "MPN" "PCA6408APW"
			(at 0 0 0)
			(layer "F.Fab")
			(hide yes)
			(effects
				(font
					(size 1 1)
					(thickness 0.15)
				)
			)
		)
		(property "Manufacturer" "NXP"
			(at 0 0 0)
			(layer "F.Fab")
			(hide yes)
			(effects
				(font
					(size 1 1)
					(thickness 0.15)
				)
			)
		)
		(sheetname "EEPROM")
		(sheetfile "EEPROM.kicad_sch")
		(attr smd)
		(fp_line
			(start -2.149 -2.735)
			(end 2.25 -2.735)
			(stroke
				(width 0.15)
				(type solid)
			)
			(layer "F.SilkS")
		)
		(fp_line
			(start 0.051 2.733)
			(end -2.149 2.733)
			(stroke
				(width 0.15)
				(type solid)
			)
			(layer "F.SilkS")
		)
		(fp_line
			(start 0.051 2.733)
			(end 2.25 2.733)
			(stroke
				(width 0.15)
				(type solid)
			)
			(layer "F.SilkS")
		)
		(fp_circle
			(center -2.815 -3.05)
			(end -2.765 -3.05)
			(stroke
				(width 0.15)
				(type solid)
			)
			(fill yes)
			(layer "F.SilkS")
		)
		(fp_line
			(start -3.81 -2.75)
			(end -3.81 2.74)
			(stroke
				(width 0.05)
				(type solid)
			)
			(layer "F.CrtYd")
		)
		(fp_line
			(start -3.81 2.74)
			(end 3.89 2.74)
			(stroke
				(width 0.05)
				(type solid)
			)
			(layer "F.CrtYd")
		)
		(fp_line
			(start 3.89 -2.75)
			(end -3.81 -2.75)
			(stroke
				(width 0.05)
				(type solid)
			)
			(layer "F.CrtYd")
		)
		(fp_line
			(start 3.89 2.74)
			(end 3.89 -2.75)
			(stroke
				(width 0.05)
				(type solid)
			)
			(layer "F.CrtYd")
		)
		(fp_line
			(start -2.149 -1.5)
			(end -1.15 -2.5)
			(stroke
				(width 0.15)
				(type solid)
			)
			(layer "F.Fab")
		)
		(fp_line
			(start -2.149 2.499)
			(end -2.149 -1.5)
			(stroke
				(width 0.15)
				(type solid)
			)
			(layer "F.Fab")
		)
		(fp_line
			(start -1.15 -2.5)
			(end 2.25 -2.5)
			(stroke
				(width 0.15)
				(type solid)
			)
			(layer "F.Fab")
		)
		(fp_line
			(start 2.25 -2.5)
			(end 2.25 2.499)
			(stroke
				(width 0.15)
				(type solid)
			)
			(layer "F.Fab")
		)
		(fp_line
			(start 2.25 2.499)
			(end -2.149 2.499)
			(stroke
				(width 0.15)
				(type solid)
			)
			(layer "F.Fab")
		)
		(pad "1" smd rect
			(at -2.815 -2.275)
			(size 1.475 0.4)
			(layers "F.Cu" "F.Mask" "F.Paste")
			(net 50 "1V8_SYS")
			(pinfunction "VDD(I2C)")
			(pintype "power_in")
		)
		(pad "2" smd rect
			(at -2.815 -1.625)
			(size 1.475 0.4)
			(layers "F.Cu" "F.Mask" "F.Paste")
			(net 50 "1V8_SYS")
			(pinfunction "ADDR")
			(pintype "input")
		)
		(pad "3" smd rect
			(at -2.815 -0.975)
			(size 1.475 0.4)
			(layers "F.Cu" "F.Mask" "F.Paste")
			(net 50 "1V8_SYS")
			(pinfunction "~{RESET}")
			(pintype "input")
		)
		(pad "4" smd rect
			(at -2.815 -0.325)
			(size 1.475 0.4)
			(layers "F.Cu" "F.Mask" "F.Paste")
			(net 8 "Net-(IC1-P0)")
			(pinfunction "P0")
			(pintype "bidirectional")
		)
		(pad "5" smd rect
			(at -2.815 0.325)
			(size 1.475 0.4)
			(layers "F.Cu" "F.Mask" "F.Paste")
			(net 9 "Net-(IC1-P1)")
			(pinfunction "P1")
			(pintype "bidirectional")
		)
		(pad "6" smd rect
			(at -2.815 0.975)
			(size 1.475 0.4)
			(layers "F.Cu" "F.Mask" "F.Paste")
			(net 10 "Net-(IC1-P2)")
			(pinfunction "P2")
			(pintype "bidirectional")
		)
		(pad "7" smd rect
			(at -2.815 1.625)
			(size 1.475 0.4)
			(layers "F.Cu" "F.Mask" "F.Paste")
			(net 11 "Net-(IC1-P3)")
			(pinfunction "P3")
			(pintype "bidirectional")
		)
		(pad "8" smd rect
			(at -2.815 2.275)
			(size 1.475 0.4)
			(layers "F.Cu" "F.Mask" "F.Paste")
			(net 1 "GND")
			(pinfunction "GND")
			(pintype "power_in")
		)
		(pad "9" smd rect
			(at 2.91 2.275)
			(size 1.475 0.4)
			(layers "F.Cu" "F.Mask" "F.Paste")
			(net 14 "Net-(IC1-P4)")
			(pinfunction "P4")
			(pintype "bidirectional")
		)
		(pad "10" smd rect
			(at 2.91 1.625)
			(size 1.475 0.4)
			(layers "F.Cu" "F.Mask" "F.Paste")
			(net 15 "Net-(IC1-P5)")
			(pinfunction "P5")
			(pintype "bidirectional")
		)
		(pad "11" smd rect
			(at 2.91 0.975)
			(size 1.475 0.4)
			(layers "F.Cu" "F.Mask" "F.Paste")
			(net 16 "unconnected-(IC1-P6-Pad11)")
			(pinfunction "P6")
			(pintype "bidirectional+no_connect")
		)
		(pad "12" smd rect
			(at 2.91 0.325)
			(size 1.475 0.4)
			(layers "F.Cu" "F.Mask" "F.Paste")
			(net 67 "unconnected-(IC1-P7-Pad12)")
			(pinfunction "P7")
			(pintype "bidirectional+no_connect")
		)
		(pad "13" smd rect
			(at 2.91 -0.325)
			(size 1.475 0.4)
			(layers "F.Cu" "F.Mask" "F.Paste")
			(net 68 "unconnected-(IC1-~{INT}-Pad13)")
			(pinfunction "~{INT}")
			(pintype "open_collector+no_connect")
		)
		(pad "14" smd rect
			(at 2.91 -0.975)
			(size 1.475 0.4)
			(layers "F.Cu" "F.Mask" "F.Paste")
			(net 13 "SCL")
			(pinfunction "SCL")
			(pintype "open_collector")
		)
		(pad "15" smd rect
			(at 2.91 -1.625)
			(size 1.475 0.4)
			(layers "F.Cu" "F.Mask" "F.Paste")
			(net 12 "SDA")
			(pinfunction "SDA")
			(pintype "open_collector")
		)
		(pad "16" smd rect
			(at 2.91 -2.275)
			(size 1.475 0.4)
			(layers "F.Cu" "F.Mask" "F.Paste")
			(net 52 "/EEPROM/VDD_LED")
			(pinfunction "VDD(P)")
			(pintype "power_in")
		)
	)
	(footprint "antmicro-footprints:LED_0603_1608Metric_G"
		(layer "F.Cu")
		(at 127.441666 72.9 90)
		(descr "LED SMD 0603 Green")
		(tags "LED SMD 0603 Green")
		(property "Reference" "D2"
			(at 1.54 -0.671666 180)
			(layer "F.SilkS")
			(effects
				(font
					(size 0.7 0.7)
					(thickness 0.15)
				)
				(justify left bottom)
			)
		)
		(property "Value" "LED_G_0603_KP-1608CGCK"
			(at 0 1.6 90)
			(layer "F.Fab")
			(hide yes)
			(effects
				(font
					(size 0.7 0.7)
					(thickness 0.15)
				)
				(justify left bottom)
			)
		)
		(property "Author" "Antmicro"
			(at 200.341666 -54.541666 0)
			(layer "F.Fab")
			(hide yes)
			(effects
				(font
					(size 1 1)
					(thickness 0.15)
				)
			)
		)
		(property "License" "Apache-2.0"
			(at 200.341666 -54.541666 0)
			(layer "F.Fab")
			(hide yes)
			(effects
				(font
					(size 1 1)
					(thickness 0.15)
				)
			)
		)
		(property "MPN" "KP-1608CGCK"
			(at 200.341666 -54.541666 0)
			(layer "F.Fab")
			(hide yes)
			(effects
				(font
					(size 1 1)
					(thickness 0.15)
				)
			)
		)
		(property "Manufacturer" "Kingbright"
			(at 200.341666 -54.541666 0)
			(layer "F.Fab")
			(hide yes)
			(effects
				(font
					(size 1 1)
					(thickness 0.15)
				)
			)
		)
		(sheetname "EEPROM")
		(sheetfile "EEPROM.kicad_sch")
		(attr smd)
		(fp_line
			(start 0.22 -0.35)
			(end -0.22 -0.35)
			(stroke
				(width 0.15)
				(type solid)
			)
			(layer "F.SilkS")
		)
		(fp_line
			(start -1.18 -0.319)
			(end -1.18 0.321)
			(stroke
				(width 0.15)
				(type solid)
			)
			(layer "F.SilkS")
		)
		(fp_line
			(start 0.105328 0.001008)
			(end 0.24 0.001)
			(stroke
				(width 0.1)
				(type solid)
			)
			(layer "F.SilkS")
		)
		(fp_line
			(start -0.094672 0.001008)
			(end 0.105328 -0.198992)
			(stroke
				(width 0.1)
				(type solid)
			)
			(layer "F.SilkS")
		)
		(fp_line
			(start -0.094672 0.001008)
			(end -0.24 0.001008)
			(stroke
				(width 0.1)
				(type solid)
			)
			(layer "F.SilkS")
		)
		(fp_line
			(start 0.105328 0.201008)
			(end 0.105328 -0.198992)
			(stroke
				(width 0.1)
				(type solid)
			)
			(layer "F.SilkS")
		)
		(fp_line
			(start 0.105328 0.201008)
			(end -0.094672 0.001008)
			(stroke
				(width 0.1)
				(type solid)
			)
			(layer "F.SilkS")
		)
		(fp_line
			(start -0.094672 0.201008)
			(end -0.094672 -0.198992)
			(stroke
				(width 0.1)
				(type solid)
			)
			(layer "F.SilkS")
		)
		(fp_line
			(start 0.22 0.35)
			(end -0.22 0.35)
			(stroke
				(width 0.15)
				(type solid)
			)
			(layer "F.SilkS")
		)
		(fp_rect
			(start 1.25 0.65)
			(end -1.25 -0.65)
			(stroke
				(width 0.05)
				(type solid)
			)
			(fill no)
			(layer "F.CrtYd")
		)
		(fp_line
			(start 0.201 -0.202)
			(end -0.101 0)
			(stroke
				(width 0.15)
				(type solid)
			)
			(layer "F.Fab")
		)
		(fp_line
			(start -0.199 -0.202)
			(end -0.199 0.1)
			(stroke
				(width 0.15)
				(type solid)
			)
			(layer "F.Fab")
		)
		(fp_line
			(start 0.599 0)
			(end 0.201 0)
			(stroke
				(width 0.15)
				(type solid)
			)
			(layer "F.Fab")
		)
		(fp_line
			(start 0.201 0)
			(end 0.201 -0.202)
			(stroke
				(width 0.15)
				(type solid)
			)
			(layer "F.Fab")
		)
		(fp_line
			(start -0.101 0)
			(end 0.201 0.2)
			(stroke
				(width 0.15)
				(type solid)
			)
			(layer "F.Fab")
		)
		(fp_line
			(start -0.199 0)
			(end -0.597 0)
			(stroke
				(width 0.15)
				(type solid)
			)
			(layer "F.Fab")
		)
		(fp_line
			(start 0.201 0.2)
			(end 0.201 0)
			(stroke
				(width 0.15)
				(type solid)
			)
			(layer "F.Fab")
		)
		(fp_line
			(start -0.199 0.2)
			(end -0.199 0.1)
			(stroke
				(width 0.15)
				(type solid)
			)
			(layer "F.Fab")
		)
		(fp_rect
			(start 0.848 0.4)
			(end -0.85 -0.402)
			(stroke
				(width 0.15)
				(type solid)
			)
			(fill no)
			(layer "F.Fab")
		)
		(pad "1" smd roundrect
			(at -0.7 0 270)
			(size 0.8 1)
			(layers "F.Cu" "F.Mask" "F.Paste")
			(roundrect_rratio 0.2)
			(net 5 "Net-(D2-Pad1)")
			(pinfunction "1")
			(pintype "passive")
		)
		(pad "2" smd roundrect
			(at 0.7 0 270)
			(size 0.8 1)
			(layers "F.Cu" "F.Mask" "F.Paste")
			(roundrect_rratio 0.2)
			(net 1 "GND")
			(pinfunction "2")
			(pintype "passive")
		)
	)
	(footprint "antmicro-footprints:R_0402_1005Metric"
		(layer "F.Cu")
		(at 125.625 75.95 90)
		(descr "Resistor SMD 0402")
		(tags "resistor SMD 0402")
		(property "Reference" "R9"
			(at -2.5 0.345 90)
			(layer "F.SilkS")
			(effects
				(font
					(size 0.7 0.7)
					(thickness 0.15)
				)
				(justify left bottom)
			)
		)
		(property "Value" "R_220R_0402"
			(at 0 1.4 90)
			(layer "F.Fab")
			(hide yes)
			(effects
				(font
					(size 0.7 0.7)
					(thickness 0.15)
				)
				(justify left bottom)
			)
		)
		(property "Description" "220R resistor in 0402 package with 1% tolerance"
			(at 0 0 90)
			(layer "F.Fab")
			(hide yes)
			(effects
				(font
					(size 1.27 1.27)
					(thickness 0.15)
				)
			)
		)
		(property "Author" "Antmicro"
			(at 201.575 -49.675 0)
			(layer "F.Fab")
			(hide yes)
			(effects
				(font
					(size 1 1)
					(thickness 0.15)
				)
			)
		)
		(property "License" "Apache-2.0"
			(at 201.575 -49.675 0)
			(layer "F.Fab")
			(hide yes)
			(effects
				(font
					(size 1 1)
					(thickness 0.15)
				)
			)
		)
		(property "MPN" "CR0402-FX-2200GLF"
			(at 201.575 -49.675 0)
			(layer "F.Fab")
			(hide yes)
			(effects
				(font
					(size 1 1)
					(thickness 0.15)
				)
			)
		)
		(property "Manufacturer" "Bourns"
			(at 201.575 -49.675 0)
			(layer "F.Fab")
			(hide yes)
			(effects
				(font
					(size 1 1)
					(thickness 0.15)
				)
			)
		)
		(property "Tolerance" "1%"
			(at 201.575 -49.675 0)
			(layer "F.Fab")
			(hide yes)
			(effects
				(font
					(size 1 1)
					(thickness 0.15)
				)
			)
		)
		(property "Val" "220R"
			(at 201.575 -49.675 0)
			(layer "F.Fab")
			(hide yes)
			(effects
				(font
					(size 1 1)
					(thickness 0.15)
				)
			)
		)
		(sheetname "EEPROM")
		(sheetfile "EEPROM.kicad_sch")
		(attr smd)
		(fp_rect
			(start -0.925 -0.47)
			(end 0.925 0.47)
			(stroke
				(width 0.05)
				(type default)
			)
			(fill no)
			(layer "F.CrtYd")
		)
		(fp_rect
			(start -0.5 -0.25)
			(end 0.5 0.25)
			(stroke
				(width 0.15)
				(type solid)
			)
			(fill no)
			(layer "F.Fab")
		)
		(pad "1" smd roundrect
			(at -0.48 0 90)
			(size 0.59 0.64)
			(layers "F.Cu" "F.Mask" "F.Paste")
			(roundrect_rratio 0.25)
			(net 8 "Net-(IC1-P0)")
			(pintype "passive")
		)
		(pad "2" smd roundrect
			(at 0.48 0 90)
			(size 0.59 0.64)
			(layers "F.Cu" "F.Mask" "F.Paste")
			(roundrect_rratio 0.25)
			(net 4 "Net-(D1-Pad1)")
			(pintype "passive")
		)
	)
)
